(kicad_pcb
	(version 20260206)
	(generator "pcbnew")
	(generator_version "10.0")
	(general
		(thickness 1.6)
		(legacy_teardrops no)
	)
	(paper "A4")
	(title_block
		(title "Bryce Canyon_F.DPB_16315-1-OCP.brd")
		(comment 1 "Bryce Canyon / footprints 1145-1151 of 2223")
	)
	(layers
		(0 "F.Cu" signal "TOP")
		(4 "In1.Cu" signal "L2GND")
		(6 "In2.Cu" signal "L3")
		(8 "In3.Cu" signal "L4GND")
		(10 "In4.Cu" signal "L5")
		(12 "In5.Cu" signal "L6VCC")
		(14 "In6.Cu" signal "L7VCC")
		(16 "In7.Cu" signal "L8")
		(18 "In8.Cu" signal "L9GND")
		(20 "In9.Cu" signal "L10")
		(22 "In10.Cu" signal "L11GND")
		(2 "B.Cu" signal "BOTTOM")
		(9 "F.Adhes" user "F.Adhesive")
		(11 "B.Adhes" user "B.Adhesive")
		(13 "F.Paste" user "Package Geometry/Pastemask Top")
		(15 "B.Paste" user "Package Geometry/Pastemask Bottom")
		(5 "F.SilkS" user "Ref Des/Silkscreen Top")
		(7 "B.SilkS" user "Ref Des/Silkscreen Bottom")
		(1 "F.Mask" user "Board Geometry/Soldermask Top")
		(3 "B.Mask" user "Board Geometry/Soldermask Bottom")
		(17 "Dwgs.User" user "User.Drawings")
		(19 "Cmts.User" user "User.Comments")
		(21 "Eco1.User" user "User.Eco1")
		(23 "Eco2.User" user "User.Eco2")
		(25 "Edge.Cuts" user "Board Geometry/Outline")
		(27 "Margin" user)
		(31 "F.CrtYd" user "Package Geometry/Place Bound Top")
		(29 "B.CrtYd" user "Package Geometry/Place Bound Bottom")
		(35 "F.Fab" user "Ref Des/Assembly Top")
		(33 "B.Fab" user "Ref Des/Assembly Bottom")
	)
	(footprint ""
		(layer "F.Cu")
		(at 406.679654 -127.78867 180)
		(property "Reference" "Q248"
			(at 0 0 180)
			(layer "F.SilkS")
			(hide yes)
			(effects
				(font
					(size 1.27 1.27)
				)
			)
		)
		(property "Value" "2N7002K-2-GP"
			(at 0.127 -8.9662 180)
			(unlocked yes)
			(layer "F.Fab")
			(hide yes)
			(effects
				(font
					(size 1.016 1.016)
					(thickness 0.1524)
				)
			)
		)
		(property "Device Type" "SOT23DGS2D4H44"
			(at 0.127 -10.4902 180)
			(unlocked yes)
			(layer "F.Fab")
			(hide yes)
			(effects
				(font
					(size 1.016 1.016)
					(thickness 0.1524)
				)
			)
		)
		(duplicate_pad_numbers_are_jumpers no)
		(fp_line
			(start 1.651 1.778)
			(end 1.651 -1.778)
			(stroke
				(width 0.1524)
				(type default)
			)
			(layer "F.SilkS")
		)
		(fp_line
			(start 1.651 -1.778)
			(end -1.651 -1.778)
			(stroke
				(width 0.1524)
				(type default)
			)
			(layer "F.SilkS")
		)
		(fp_line
			(start -1.651 1.778)
			(end 1.651 1.778)
			(stroke
				(width 0.1524)
				(type default)
			)
			(layer "F.SilkS")
		)
		(fp_line
			(start -1.651 -1.778)
			(end -1.651 1.778)
			(stroke
				(width 0.1524)
				(type default)
			)
			(layer "F.SilkS")
		)
		(fp_poly
			(pts
				(xy -1.778 1.8796) (xy -1.778 -1.8796) (xy 1.778 -1.8796) (xy 1.778 1.8796)
			)
			(stroke
				(width 0)
				(type default)
			)
			(fill no)
			(layer "F.CrtYd")
		)
		(fp_poly
			(pts
				(xy -1.778 1.8796) (xy -1.778 -1.8796) (xy 1.778 -1.8796) (xy 1.778 1.8796)
			)
			(stroke
				(width 0)
				(type default)
			)
			(fill no)
			(layer "F.Fab")
		)
		(pad "D" smd custom
			(at 0 -0.9525 180)
			(size 0.1905 0.1905)
			(layers "F.Cu" "F.Mask" "F.Paste")
			(net "FLT_HDD21_N")
			(options
				(clearance outline)
				(anchor circle)
			)
			(primitives
				(gr_poly
					(pts
						(arc
							(start -0.1778 0.5715)
							(mid -0.321484 0.511984)
							(end -0.381 0.3683)
						)
						(arc
							(start -0.381 -0.3683)
							(mid -0.321484 -0.511984)
							(end -0.1778 -0.5715)
						)
						(arc
							(start 0.1778 -0.5715)
							(mid 0.321484 -0.511984)
							(end 0.381 -0.3683)
						)
						(arc
							(start 0.381 0.3683)
							(mid 0.321484 0.511984)
							(end 0.1778 0.5715)
						)
					)
					(width 0)
					(fill yes)
				)
			)
		)
		(pad "G" smd custom
			(at -0.98425 0.9525 180)
			(size 0.1905 0.1905)
			(layers "F.Cu" "F.Mask" "F.Paste")
			(net "DRIVE_A_21_FLT_LED")
			(options
				(clearance outline)
				(anchor circle)
			)
			(primitives
				(gr_poly
					(pts
						(arc
							(start -0.1778 0.5715)
							(mid -0.321484 0.511984)
							(end -0.381 0.3683)
						)
						(arc
							(start -0.381 -0.3683)
							(mid -0.321484 -0.511984)
							(end -0.1778 -0.5715)
						)
						(arc
							(start 0.1778 -0.5715)
							(mid 0.321484 -0.511984)
							(end 0.381 -0.3683)
						)
						(arc
							(start 0.381 0.3683)
							(mid 0.321484 0.511984)
							(end 0.1778 0.5715)
						)
					)
					(width 0)
					(fill yes)
				)
			)
		)
		(pad "S" smd custom
			(at 0.98425 0.9525 180)
			(size 0.1905 0.1905)
			(layers "F.Cu" "F.Mask" "F.Paste")
			(net "GND")
			(options
				(clearance outline)
				(anchor circle)
			)
			(primitives
				(gr_poly
					(pts
						(arc
							(start -0.1778 0.5715)
							(mid -0.321484 0.511984)
							(end -0.381 0.3683)
						)
						(arc
							(start -0.381 -0.3683)
							(mid -0.321484 -0.511984)
							(end -0.1778 -0.5715)
						)
						(arc
							(start 0.1778 -0.5715)
							(mid 0.321484 -0.511984)
							(end 0.381 -0.3683)
						)
						(arc
							(start 0.381 0.3683)
							(mid 0.321484 0.511984)
							(end 0.1778 0.5715)
						)
					)
					(width 0)
					(fill yes)
				)
			)
		)
	)
	(footprint ""
		(layer "F.Cu")
		(at 115.334796 -55.285894 180)
		(property "Reference" "Q161"
			(at 0 0 180)
			(layer "F.SilkS")
			(hide yes)
			(effects
				(font
					(size 1.27 1.27)
				)
			)
		)
		(property "Value" "AO4406AL-GP"
			(at -3.707384 -1.5367 180)
			(unlocked yes)
			(layer "F.Fab")
			(hide yes)
			(effects
				(font
					(size 1.016 1.016)
					(thickness 0.1524)
				)
			)
		)
		(property "Device Type" "SOIC8H69"
			(at -3.707384 -3.0607 180)
			(unlocked yes)
			(layer "F.Fab")
			(hide yes)
			(effects
				(font
					(size 1.016 1.016)
					(thickness 0.1524)
				)
			)
		)
		(duplicate_pad_numbers_are_jumpers no)
		(fp_line
			(start 2.1336 1.4224)
			(end 2.1336 -1.4224)
			(stroke
				(width 0.1524)
				(type default)
			)
			(layer "F.SilkS")
		)
		(fp_line
			(start 2.1336 -1.4224)
			(end -2.7432 -1.4224)
			(stroke
				(width 0.1524)
				(type default)
			)
			(layer "F.SilkS")
		)
		(fp_line
			(start -2.1844 -0.0508)
			(end -2.7178 0.508)
			(stroke
				(width 0.1524)
				(type default)
			)
			(layer "F.SilkS")
		)
		(fp_line
			(start -2.6289 3.4417)
			(end -2.6289 1.4732)
			(stroke
				(width 0.381)
				(type default)
			)
			(layer "F.SilkS")
		)
		(fp_line
			(start -2.7178 -0.508)
			(end -2.1844 -0.0508)
			(stroke
				(width 0.1524)
				(type default)
			)
			(layer "F.SilkS")
		)
		(fp_line
			(start -2.7432 1.4224)
			(end 2.1336 1.4224)
			(stroke
				(width 0.1524)
				(type default)
			)
			(layer "F.SilkS")
		)
		(fp_line
			(start -2.7432 1.4224)
			(end -2.6416 1.4224)
			(stroke
				(width 0.1524)
				(type default)
			)
			(layer "F.SilkS")
		)
		(fp_line
			(start -2.7432 -1.4224)
			(end -2.7432 1.4224)
			(stroke
				(width 0.1524)
				(type default)
			)
			(layer "F.SilkS")
		)
		(fp_poly
			(pts
				(xy -2.2098 -1.4224) (xy -2.2098 1.4224) (xy 2.2098 1.4224) (xy 2.2098 -1.4224)
			)
			(stroke
				(width 0)
				(type default)
			)
			(fill yes)
			(layer "F.SilkS")
		)
		(fp_rect
			(start -2.450084 2.999994)
			(end 2.450084 -2.999994)
			(stroke
				(width 0)
				(type default)
			)
			(fill no)
			(layer "F.CrtYd")
		)
		(fp_poly
			(pts
				(xy -2.8194 3.6322) (xy -2.8194 -3.6322) (xy 2.8194 -3.6322) (xy 2.8194 1.18364) (xy 2.450084 1.18364)
				(xy 2.450084 -2.999994) (xy -2.450084 -2.999994) (xy -2.450084 2.999994) (xy 2.450084 2.999994)
				(xy 2.450084 1.18618) (xy 2.8194 1.18618) (xy 2.8194 3.6322)
			)
			(stroke
				(width 0)
				(type default)
			)
			(fill no)
			(layer "F.CrtYd")
		)
		(fp_rect
			(start -2.8194 3.6322)
			(end 2.8194 -3.6322)
			(stroke
				(width 0)
				(type default)
			)
			(fill no)
			(layer "F.Fab")
		)
		(pad "1" smd rect
			(at -1.905 2.54 180)
			(size 0.635 1.651)
			(layers "F.Cu" "F.Mask" "F.Paste")
			(net "P5V_HDD27")
		)
		(pad "2" smd rect
			(at -0.635 2.54 180)
			(size 0.635 1.651)
			(layers "F.Cu" "F.Mask" "F.Paste")
			(net "P5V_HDD27")
		)
		(pad "3" smd rect
			(at 0.635 2.54 180)
			(size 0.635 1.651)
			(layers "F.Cu" "F.Mask" "F.Paste")
			(net "P5V_HDD27")
		)
		(pad "4" smd rect
			(at 1.905 2.54 180)
			(size 0.635 1.651)
			(layers "F.Cu" "F.Mask" "F.Paste")
			(net "SW_HDD_P27")
		)
		(pad "5" smd rect
			(at 1.905 -2.54 180)
			(size 0.635 1.651)
			(layers "F.Cu" "F.Mask" "F.Paste")
			(net "P5V_A_2")
		)
		(pad "6" smd rect
			(at 0.635 -2.54 180)
			(size 0.635 1.651)
			(layers "F.Cu" "F.Mask" "F.Paste")
			(net "P5V_A_2")
		)
		(pad "7" smd rect
			(at -0.635 -2.54 180)
			(size 0.635 1.651)
			(layers "F.Cu" "F.Mask" "F.Paste")
			(net "P5V_A_2")
		)
		(pad "8" smd rect
			(at -1.905 -2.54 180)
			(size 0.635 1.651)
			(layers "F.Cu" "F.Mask" "F.Paste")
			(net "P5V_A_2")
		)
	)
	(footprint ""
		(layer "F.Cu")
		(at 252.73 -290.195 180)
		(property "Reference" "R1"
			(at 0 0 180)
			(layer "F.SilkS")
			(hide yes)
			(effects
				(font
					(size 1.27 1.27)
				)
			)
		)
		(property "Value" "4K7R2F-GP"
			(at 0.064008 -3.993896 180)
			(unlocked yes)
			(layer "F.Fab")
			(hide yes)
			(effects
				(font
					(size 1.016 1.016)
					(thickness 0.1524)
				)
			)
		)
		(property "Device Type" "R402H16"
			(at 0.064008 -5.517896 180)
			(unlocked yes)
			(layer "F.Fab")
			(hide yes)
			(effects
				(font
					(size 1.016 1.016)
					(thickness 0.1524)
				)
			)
		)
		(duplicate_pad_numbers_are_jumpers no)
		(fp_line
			(start 0.508 -0.9398)
			(end -0.508 -0.9398)
			(stroke
				(width 0.1524)
				(type default)
			)
			(layer "F.SilkS")
		)
		(fp_line
			(start -0.508 -0.9398)
			(end -0.508 0.9398)
			(stroke
				(width 0.1524)
				(type default)
			)
			(layer "F.SilkS")
		)
		(fp_rect
			(start -0.508 0.9398)
			(end 0.508 -0.9398)
			(stroke
				(width 0)
				(type default)
			)
			(fill no)
			(layer "F.CrtYd")
		)
		(fp_rect
			(start -0.508 0.9398)
			(end 0.508 -0.9398)
			(stroke
				(width 0)
				(type default)
			)
			(fill no)
			(layer "F.Fab")
		)
		(pad "1" smd custom
			(at 0 -0.4445 180)
			(size 0.1397 0.1397)
			(layers "F.Cu" "F.Mask" "F.Paste")
			(net "P3V3_STBY_A")
			(options
				(clearance outline)
				(anchor circle)
			)
			(primitives
				(gr_poly
					(pts
						(arc
							(start -0.1778 -0.2794)
							(mid -0.249642 -0.249642)
							(end -0.2794 -0.1778)
						)
						(arc
							(start -0.2794 0.1778)
							(mid -0.249642 0.249642)
							(end -0.1778 0.2794)
						)
						(arc
							(start 0.1778 0.2794)
							(mid 0.249642 0.249642)
							(end 0.2794 0.1778)
						)
						(arc
							(start 0.2794 -0.1778)
							(mid 0.249642 -0.249642)
							(end 0.1778 -0.2794)
						)
					)
					(width 0)
					(fill yes)
				)
			)
		)
		(pad "2" smd custom
			(at 0 0.4445 180)
			(size 0.1397 0.1397)
			(layers "F.Cu" "F.Mask" "F.Paste")
			(net "EEPROM_A0")
			(options
				(clearance outline)
				(anchor circle)
			)
			(primitives
				(gr_poly
					(pts
						(arc
							(start -0.1778 -0.2794)
							(mid -0.249642 -0.249642)
							(end -0.2794 -0.1778)
						)
						(arc
							(start -0.2794 0.1778)
							(mid -0.249642 0.249642)
							(end -0.1778 0.2794)
						)
						(arc
							(start 0.1778 0.2794)
							(mid 0.249642 0.249642)
							(end 0.2794 0.1778)
						)
						(arc
							(start 0.2794 -0.1778)
							(mid 0.249642 -0.249642)
							(end 0.1778 -0.2794)
						)
					)
					(width 0)
					(fill yes)
				)
			)
		)
	)
	(footprint ""
		(layer "F.Cu")
		(at 224.528126 -139.239498 -90)
		(property "Reference" "TP226"
			(at 0 0 270)
			(layer "F.SilkS")
			(hide yes)
			(effects
				(font
					(size 1.27 1.27)
				)
			)
		)
		(property "Value" "TPAD32-GP"
			(at -0.0508 -1.6764 270)
			(unlocked yes)
			(layer "F.Fab")
			(hide yes)
			(effects
				(font
					(size 1.016 1.016)
					(thickness 0.1524)
				)
			)
		)
		(property "Device Type" "TPAD32"
			(at -0.0508 -3.2004 270)
			(unlocked yes)
			(layer "F.Fab")
			(hide yes)
			(effects
				(font
					(size 1.016 1.016)
					(thickness 0.1524)
				)
			)
		)
		(duplicate_pad_numbers_are_jumpers no)
		(fp_poly
			(pts
				(arc
					(start 0 -0.4064)
					(mid 0 0.4064)
					(end 0 -0.4064)
				)
			)
			(stroke
				(width 0)
				(type default)
			)
			(fill no)
			(layer "F.CrtYd")
		)
		(fp_poly
			(pts
				(arc
					(start 0 -0.7112)
					(mid 0 0.7112)
					(end 0 -0.7112)
				)
			)
			(stroke
				(width 0)
				(type default)
			)
			(fill no)
			(layer "F.Fab")
		)
		(pad "1" smd circle
			(at 0 0 270)
			(size 0.8128 0.8128)
			(layers "F.Cu" "F.Mask" "F.Paste")
			(net "TP_SMB_COMP_A_NIC_ALERT_N")
		)
	)
	(footprint ""
		(layer "F.Cu")
		(at 331.47 -291.127942 -90)
		(property "Reference" "R267"
			(at 0 0 270)
			(layer "F.SilkS")
			(hide yes)
			(effects
				(font
					(size 1.27 1.27)
				)
			)
		)
		(property "Value" "2R6F-GP"
			(at -0.0508 -4.8514 270)
			(unlocked yes)
			(layer "F.Fab")
			(hide yes)
			(effects
				(font
					(size 1.016 1.016)
					(thickness 0.1524)
				)
			)
		)
		(property "Device Type" "R1206H26"
			(at 0 -6.3754 270)
			(unlocked yes)
			(layer "F.Fab")
			(hide yes)
			(effects
				(font
					(size 1.016 1.016)
					(thickness 0.1524)
				)
			)
		)
		(duplicate_pad_numbers_are_jumpers no)
		(fp_line
			(start -1.016 2.2352)
			(end -1.016 -2.2352)
			(stroke
				(width 0.1524)
				(type default)
			)
			(layer "F.SilkS")
		)
		(fp_line
			(start 1.016 2.2352)
			(end -1.016 2.2352)
			(stroke
				(width 0.1524)
				(type default)
			)
			(layer "F.SilkS")
		)
		(fp_line
			(start -1.016 -2.2352)
			(end 1.016 -2.2352)
			(stroke
				(width 0.1524)
				(type default)
			)
			(layer "F.SilkS")
		)
		(fp_line
			(start 1.016 -2.2352)
			(end 1.016 2.2352)
			(stroke
				(width 0.1524)
				(type default)
			)
			(layer "F.SilkS")
		)
		(fp_rect
			(start -1.0922 2.3114)
			(end 1.0922 -2.3114)
			(stroke
				(width 0)
				(type default)
			)
			(fill no)
			(layer "F.CrtYd")
		)
		(fp_poly
			(pts
				(xy -1.0922 -2.3114) (xy 1.0922 -2.3114) (xy 1.0922 2.3114) (xy -1.0922 2.3114)
			)
			(stroke
				(width 0)
				(type default)
			)
			(fill no)
			(layer "F.Fab")
		)
		(pad "1" smd rect
			(at 0 -1.397 270)
			(size 1.651 1.27)
			(layers "F.Cu" "F.Mask" "F.Paste")
			(net "P5V_HDD6")
		)
		(pad "2" smd rect
			(at 0 1.397 270)
			(size 1.651 1.27)
			(layers "F.Cu" "F.Mask" "F.Paste")
			(net "5V_PRE_6")
		)
	)
	(footprint ""
		(layer "F.Cu")
		(at 363.020102 -176.127918 -90)
		(property "Reference" "R566"
			(at 0 0 270)
			(layer "F.SilkS")
			(hide yes)
			(effects
				(font
					(size 1.27 1.27)
				)
			)
		)
		(property "Value" "2R6F-GP"
			(at -0.0508 -4.8514 270)
			(unlocked yes)
			(layer "F.Fab")
			(hide yes)
			(effects
				(font
					(size 1.016 1.016)
					(thickness 0.1524)
				)
			)
		)
		(property "Device Type" "R1206H26"
			(at 0 -6.3754 270)
			(unlocked yes)
			(layer "F.Fab")
			(hide yes)
			(effects
				(font
					(size 1.016 1.016)
					(thickness 0.1524)
				)
			)
		)
		(duplicate_pad_numbers_are_jumpers no)
		(fp_line
			(start -1.016 2.2352)
			(end -1.016 -2.2352)
			(stroke
				(width 0.1524)
				(type default)
			)
			(layer "F.SilkS")
		)
		(fp_line
			(start 1.016 2.2352)
			(end -1.016 2.2352)
			(stroke
				(width 0.1524)
				(type default)
			)
			(layer "F.SilkS")
		)
		(fp_line
			(start -1.016 -2.2352)
			(end 1.016 -2.2352)
			(stroke
				(width 0.1524)
				(type default)
			)
			(layer "F.SilkS")
		)
		(fp_line
			(start 1.016 -2.2352)
			(end 1.016 2.2352)
			(stroke
				(width 0.1524)
				(type default)
			)
			(layer "F.SilkS")
		)
		(fp_rect
			(start -1.0922 2.3114)
			(end 1.0922 -2.3114)
			(stroke
				(width 0)
				(type default)
			)
			(fill no)
			(layer "F.CrtYd")
		)
		(fp_poly
			(pts
				(xy -1.0922 -2.3114) (xy 1.0922 -2.3114) (xy 1.0922 2.3114) (xy -1.0922 2.3114)
			)
			(stroke
				(width 0)
				(type default)
			)
			(fill no)
			(layer "F.Fab")
		)
		(pad "1" smd rect
			(at 0 -1.397 270)
			(size 1.651 1.27)
			(layers "F.Cu" "F.Mask" "F.Paste")
			(net "P5V_HDD19")
		)
		(pad "2" smd rect
			(at 0 1.397 270)
			(size 1.651 1.27)
			(layers "F.Cu" "F.Mask" "F.Paste")
			(net "5V_PRE_19")
		)
	)
	(footprint ""
		(layer "F.Cu")
		(at 229.849934 -143.49984)
		(property "Reference" ""
			(at 0 0 0)
			(layer "F.SilkS")
			(hide yes)
			(effects
				(font
					(size 1.27 1.27)
				)
			)
		)
		(property "Value" "*"
			(at -4.729734 -0.095504 0)
			(unlocked yes)
			(layer "F.Fab")
			(hide yes)
			(effects
				(font
					(size 1.016 1.016)
					(thickness 0.1524)
				)
			)
		)
		(duplicate_pad_numbers_are_jumpers no)
		(fp_poly
			(pts
				(arc
					(start 4.064 0)
					(mid -4.064 0)
					(end 4.064 0)
				)
			)
			(stroke
				(width 0)
				(type default)
			)
			(fill no)
			(layer "B.CrtYd")
		)
		(fp_poly
			(pts
				(arc
					(start 4.064 0)
					(mid -4.064 0)
					(end 4.064 0)
				)
			)
			(stroke
				(width 0)
				(type default)
			)
			(fill no)
			(layer "F.CrtYd")
		)
		(fp_poly
			(pts
				(arc
					(start 4.064 0)
					(mid -4.064 0)
					(end 4.064 0)
				)
			)
			(stroke
				(width 0)
				(type default)
			)
			(fill no)
			(layer "B.Fab")
		)
		(fp_poly
			(pts
				(arc
					(start 4.064 0)
					(mid -4.064 0)
					(end 4.064 0)
				)
			)
			(stroke
				(width 0)
				(type default)
			)
			(fill no)
			(layer "F.Fab")
		)
		(pad "1" thru_hole circle
			(at 0 0)
			(size 7.5184 7.5184)
			(drill 4.2164)
			(layers "*.Cu" "*.Mask")
			(remove_unused_layers no)
			(net "Net_60")
			(clearance -1.143)
			(thermal_gap 0.3048)
			(padstack
				(mode front_inner_back)
				(layer "Inner"
					(shape circle)
					(size 4.6228 4.6228)
					(clearance 0.3048)
				)
				(layer "B.Cu"
					(shape circle)
					(size 7.5184 7.5184)
					(clearance -1.143)
				)
			)
		)
	)
)
